(kicad_pcb
	(version 20260206)
	(generator "pcbnew")
	(generator_version "10.0")
	(general
		(thickness 1.6)
		(legacy_teardrops no)
	)
	(paper "A4")
	(title_block
		(title "pdpb — Lightning_PDPB_BRD.brd")
		(comment 1 "Lightning (Wiwynn / Facebook NVMe JBOF) / footprints 179-184 of 1140")
	)
	(layers
		(0 "F.Cu" signal "TOP")
		(4 "In1.Cu" signal "L2GND")
		(6 "In2.Cu" signal "L3")
		(8 "In3.Cu" signal "L4VCC")
		(10 "In4.Cu" signal "L5VCC")
		(12 "In5.Cu" signal "L6")
		(14 "In6.Cu" signal "L7GND")
		(2 "B.Cu" signal "BOTTOM")
		(9 "F.Adhes" user "F.Adhesive")
		(11 "B.Adhes" user "B.Adhesive")
		(13 "F.Paste" user "Package Geometry/Pastemask Top")
		(15 "B.Paste" user "Package Geometry/Pastemask Bottom")
		(5 "F.SilkS" user "Ref Des/Silkscreen Top")
		(7 "B.SilkS" user "Ref Des/Silkscreen Bottom")
		(1 "F.Mask" user "Board Geometry/Soldermask Top")
		(3 "B.Mask" user "Board Geometry/Soldermask Bottom")
		(17 "Dwgs.User" user "User.Drawings")
		(19 "Cmts.User" user "User.Comments")
		(21 "Eco1.User" user "User.Eco1")
		(23 "Eco2.User" user "User.Eco2")
		(25 "Edge.Cuts" user "Board Geometry/Outline")
		(27 "Margin" user)
		(31 "F.CrtYd" user "Package Geometry/Place Bound Top")
		(29 "B.CrtYd" user "Package Geometry/Place Bound Bottom")
		(35 "F.Fab" user "Ref Des/Assembly Top")
		(33 "B.Fab" user "Ref Des/Assembly Bottom")
	)
	(footprint ""
		(layer "F.Cu")
		(at 27.9146 -498.5258 180)
		(property "Reference" "PC1205"
			(at 0 0 180)
			(layer "F.SilkS")
			(hide yes)
			(effects
				(font
					(size 1.27 1.27)
				)
			)
		)
		(property "Value" "SC22U25V6KX-GP-U"
			(at -2.860802 -5.279644 180)
			(unlocked yes)
			(layer "F.Fab")
			(hide yes)
			(effects
				(font
					(size 1.016 1.016)
					(thickness 0.1524)
				)
			)
		)
		(property "Device Type" "C1206-TO0D3H75"
			(at -2.860802 -6.803644 180)
			(unlocked yes)
			(layer "F.Fab")
			(hide yes)
			(effects
				(font
					(size 1.016 1.016)
					(thickness 0.1524)
				)
			)
		)
		(duplicate_pad_numbers_are_jumpers no)
		(fp_line
			(start 1.3081 2.3749)
			(end -1.3081 2.3749)
			(stroke
				(width 0.1524)
				(type default)
			)
			(layer "F.SilkS")
		)
		(fp_line
			(start 1.3081 -2.3749)
			(end 1.3081 2.3749)
			(stroke
				(width 0.1524)
				(type default)
			)
			(layer "F.SilkS")
		)
		(fp_line
			(start -1.3081 2.3749)
			(end -1.3081 -2.3749)
			(stroke
				(width 0.1524)
				(type default)
			)
			(layer "F.SilkS")
		)
		(fp_line
			(start -1.3081 -2.3749)
			(end 1.3081 -2.3749)
			(stroke
				(width 0.1524)
				(type default)
			)
			(layer "F.SilkS")
		)
		(fp_rect
			(start -0.8001 1.6002)
			(end 0.8001 -1.6002)
			(stroke
				(width 0)
				(type default)
			)
			(fill no)
			(layer "F.CrtYd")
		)
		(fp_poly
			(pts
				(xy -1.5621 2.4511) (xy -1.5621 1.6002) (xy 0.8001 1.6002) (xy 0.8001 -1.6002) (xy -0.8001 -1.6002)
				(xy -0.8001 1.5875) (xy -1.5621 1.5875) (xy -1.5621 -2.4511) (xy 1.5621 -2.4511) (xy 1.5621 2.4511)
			)
			(stroke
				(width 0)
				(type default)
			)
			(fill no)
			(layer "F.CrtYd")
		)
		(fp_rect
			(start -1.5621 2.4511)
			(end 1.5621 -2.4511)
			(stroke
				(width 0)
				(type default)
			)
			(fill no)
			(layer "F.Fab")
		)
		(pad "1" smd rect
			(at 0 -1.392936 180)
			(size 2.1082 1.4478)
			(layers "F.Cu" "F.Mask" "F.Paste")
			(net "P12V_SSD5")
		)
		(pad "2" smd rect
			(at 0 1.392936 180)
			(size 2.1082 1.4478)
			(layers "F.Cu" "F.Mask" "F.Paste")
			(net "GND")
		)
	)
	(footprint ""
		(layer "F.Cu")
		(at 82.931 -107.95 90)
		(property "Reference" "R9358"
			(at 0 0 90)
			(layer "F.SilkS")
			(hide yes)
			(effects
				(font
					(size 1.27 1.27)
				)
			)
		)
		(property "Value" "2D2R2F-GP"
			(at 0.064008 -3.993896 90)
			(unlocked yes)
			(layer "F.Fab")
			(hide yes)
			(effects
				(font
					(size 1.016 1.016)
					(thickness 0.1524)
				)
			)
		)
		(property "Device Type" "R402H16"
			(at 0.064008 -5.517896 90)
			(unlocked yes)
			(layer "F.Fab")
			(hide yes)
			(effects
				(font
					(size 1.016 1.016)
					(thickness 0.1524)
				)
			)
		)
		(duplicate_pad_numbers_are_jumpers no)
		(fp_line
			(start 0.508 -0.9398)
			(end -0.508 -0.9398)
			(stroke
				(width 0.1524)
				(type default)
			)
			(layer "F.SilkS")
		)
		(fp_line
			(start -0.508 -0.9398)
			(end -0.508 0.9398)
			(stroke
				(width 0.1524)
				(type default)
			)
			(layer "F.SilkS")
		)
		(fp_rect
			(start -0.508 0.9398)
			(end 0.508 -0.9398)
			(stroke
				(width 0)
				(type default)
			)
			(fill no)
			(layer "F.CrtYd")
		)
		(fp_rect
			(start -0.508 0.9398)
			(end 0.508 -0.9398)
			(stroke
				(width 0)
				(type default)
			)
			(fill no)
			(layer "F.Fab")
		)
		(pad "1" smd custom
			(at 0 -0.4445 90)
			(size 0.1397 0.1397)
			(layers "F.Cu" "F.Mask" "F.Paste")
			(net "VDD_DIFF_4")
			(options
				(clearance outline)
				(anchor circle)
			)
			(primitives
				(gr_poly
					(pts
						(arc
							(start -0.1778 -0.2794)
							(mid -0.249642 -0.249642)
							(end -0.2794 -0.1778)
						)
						(arc
							(start -0.2794 0.1778)
							(mid -0.249642 0.249642)
							(end -0.1778 0.2794)
						)
						(arc
							(start 0.1778 0.2794)
							(mid 0.249642 0.249642)
							(end 0.2794 0.1778)
						)
						(arc
							(start 0.2794 -0.1778)
							(mid 0.249642 -0.249642)
							(end 0.1778 -0.2794)
						)
					)
					(width 0)
					(fill yes)
				)
			)
		)
		(pad "2" smd custom
			(at 0 0.4445 90)
			(size 0.1397 0.1397)
			(layers "F.Cu" "F.Mask" "F.Paste")
			(net "VDDA_4")
			(options
				(clearance outline)
				(anchor circle)
			)
			(primitives
				(gr_poly
					(pts
						(arc
							(start -0.1778 -0.2794)
							(mid -0.249642 -0.249642)
							(end -0.2794 -0.1778)
						)
						(arc
							(start -0.2794 0.1778)
							(mid -0.249642 0.249642)
							(end -0.1778 0.2794)
						)
						(arc
							(start 0.1778 0.2794)
							(mid 0.249642 0.249642)
							(end 0.2794 0.1778)
						)
						(arc
							(start 0.2794 -0.1778)
							(mid 0.249642 -0.249642)
							(end 0.1778 -0.2794)
						)
					)
					(width 0)
					(fill yes)
				)
			)
		)
	)
	(footprint ""
		(layer "F.Cu")
		(at 48.26 -242.062 180)
		(property "Reference" "U204"
			(at 0 0 180)
			(layer "F.SilkS")
			(hide yes)
			(effects
				(font
					(size 1.27 1.27)
				)
			)
		)
		(property "Value" "SN74LVC1G08DCKR-GP"
			(at -2.3368 -8.6868 180)
			(unlocked yes)
			(layer "F.Fab")
			(hide yes)
			(effects
				(font
					(size 1.016 1.016)
					(thickness 0.1524)
				)
			)
		)
		(property "Device Type" "SC70-5H44"
			(at -2.3114 -10.414 180)
			(unlocked yes)
			(layer "F.Fab")
			(hide yes)
			(effects
				(font
					(size 1.016 1.016)
					(thickness 0.1524)
				)
			)
		)
		(duplicate_pad_numbers_are_jumpers no)
		(fp_line
			(start 1.3843 -1.8034)
			(end 1.3843 -1.1176)
			(stroke
				(width 0.3302)
				(type default)
			)
			(layer "F.SilkS")
		)
		(fp_line
			(start 1.27 1.7018)
			(end -1.27 1.7018)
			(stroke
				(width 0.1524)
				(type default)
			)
			(layer "F.SilkS")
		)
		(fp_line
			(start 1.27 -1.7018)
			(end 1.27 1.7018)
			(stroke
				(width 0.1524)
				(type default)
			)
			(layer "F.SilkS")
		)
		(fp_line
			(start 0.6604 -1.8034)
			(end 1.3843 -1.8034)
			(stroke
				(width 0.3302)
				(type default)
			)
			(layer "F.SilkS")
		)
		(fp_line
			(start -1.27 1.7018)
			(end -1.27 -1.7018)
			(stroke
				(width 0.1524)
				(type default)
			)
			(layer "F.SilkS")
		)
		(fp_line
			(start -1.27 -1.7018)
			(end 1.27 -1.7018)
			(stroke
				(width 0.1524)
				(type default)
			)
			(layer "F.SilkS")
		)
		(fp_rect
			(start -1.524 1.9558)
			(end 1.524 -1.9558)
			(stroke
				(width 0)
				(type default)
			)
			(fill no)
			(layer "F.CrtYd")
		)
		(fp_poly
			(pts
				(xy -1.524 -1.9558) (xy 1.524 -1.9558) (xy 1.524 1.9558) (xy -1.524 1.9558)
			)
			(stroke
				(width 0)
				(type default)
			)
			(fill no)
			(layer "F.Fab")
		)
		(pad "1" smd rect
			(at 0.65024 -0.8255 180)
			(size 0.4064 1.2192)
			(layers "F.Cu" "F.Mask" "F.Paste")
			(net "SSD7_CLK0_OE_MOS_N")
		)
		(pad "2" smd rect
			(at 0 -0.8255 180)
			(size 0.4064 1.2192)
			(layers "F.Cu" "F.Mask" "F.Paste")
			(net "ATTN_LED_DR7_N")
		)
		(pad "3" smd rect
			(at -0.65024 -0.8255 180)
			(size 0.4064 1.2192)
			(layers "F.Cu" "F.Mask" "F.Paste")
			(net "GND")
		)
		(pad "4" smd rect
			(at -0.65024 0.8255 180)
			(size 0.4064 1.2192)
			(layers "F.Cu" "F.Mask" "F.Paste")
			(net "ATTN_LED_DR7_AND")
		)
		(pad "5" smd rect
			(at 0.65024 0.8255 180)
			(size 0.4064 1.2192)
			(layers "F.Cu" "F.Mask" "F.Paste")
			(net "P3V3")
		)
	)
	(footprint ""
		(layer "F.Cu")
		(at 38.1 -137.922 180)
		(property "Reference" "R9836"
			(at 0 0 180)
			(layer "F.SilkS")
			(hide yes)
			(effects
				(font
					(size 1.27 1.27)
				)
			)
		)
		(property "Value" "0R2J-2-GP"
			(at 0.064008 -3.993896 180)
			(unlocked yes)
			(layer "F.Fab")
			(hide yes)
			(effects
				(font
					(size 1.016 1.016)
					(thickness 0.1524)
				)
			)
		)
		(property "Device Type" "R402H16"
			(at 0.064008 -5.517896 180)
			(unlocked yes)
			(layer "F.Fab")
			(hide yes)
			(effects
				(font
					(size 1.016 1.016)
					(thickness 0.1524)
				)
			)
		)
		(duplicate_pad_numbers_are_jumpers no)
		(fp_line
			(start 0.508 -0.9398)
			(end -0.508 -0.9398)
			(stroke
				(width 0.1524)
				(type default)
			)
			(layer "F.SilkS")
		)
		(fp_line
			(start -0.508 -0.9398)
			(end -0.508 0.9398)
			(stroke
				(width 0.1524)
				(type default)
			)
			(layer "F.SilkS")
		)
		(fp_rect
			(start -0.508 0.9398)
			(end 0.508 -0.9398)
			(stroke
				(width 0)
				(type default)
			)
			(fill no)
			(layer "F.CrtYd")
		)
		(fp_rect
			(start -0.508 0.9398)
			(end 0.508 -0.9398)
			(stroke
				(width 0)
				(type default)
			)
			(fill no)
			(layer "F.Fab")
		)
		(pad "1" smd custom
			(at 0 -0.4445 180)
			(size 0.1397 0.1397)
			(layers "F.Cu" "F.Mask" "F.Paste")
			(net "ATTN_LED_DR8_R")
			(options
				(clearance outline)
				(anchor circle)
			)
			(primitives
				(gr_poly
					(pts
						(arc
							(start -0.1778 -0.2794)
							(mid -0.249642 -0.249642)
							(end -0.2794 -0.1778)
						)
						(arc
							(start -0.2794 0.1778)
							(mid -0.249642 0.249642)
							(end -0.1778 0.2794)
						)
						(arc
							(start 0.1778 0.2794)
							(mid 0.249642 0.249642)
							(end 0.2794 0.1778)
						)
						(arc
							(start 0.2794 -0.1778)
							(mid 0.249642 -0.249642)
							(end 0.1778 -0.2794)
						)
					)
					(width 0)
					(fill yes)
				)
			)
		)
		(pad "2" smd custom
			(at 0 0.4445 180)
			(size 0.1397 0.1397)
			(layers "F.Cu" "F.Mask" "F.Paste")
			(net "ATTN_LED_DR8_N")
			(options
				(clearance outline)
				(anchor circle)
			)
			(primitives
				(gr_poly
					(pts
						(arc
							(start -0.1778 -0.2794)
							(mid -0.249642 -0.249642)
							(end -0.2794 -0.1778)
						)
						(arc
							(start -0.2794 0.1778)
							(mid -0.249642 0.249642)
							(end -0.1778 0.2794)
						)
						(arc
							(start 0.1778 0.2794)
							(mid 0.249642 0.249642)
							(end 0.2794 0.1778)
						)
						(arc
							(start 0.2794 -0.1778)
							(mid 0.249642 -0.249642)
							(end 0.1778 -0.2794)
						)
					)
					(width 0)
					(fill yes)
				)
			)
		)
	)
	(footprint ""
		(layer "F.Cu")
		(at 24.892 -56.88711 90)
		(property "Reference" "Q99"
			(at 0 0 90)
			(layer "F.SilkS")
			(hide yes)
			(effects
				(font
					(size 1.27 1.27)
				)
			)
		)
		(property "Value" "2N7002A-7-GP"
			(at 0.127 -8.9662 90)
			(unlocked yes)
			(layer "F.Fab")
			(hide yes)
			(effects
				(font
					(size 1.016 1.016)
					(thickness 0.1524)
				)
			)
		)
		(property "Device Type" "SOT23DGS2D4H48"
			(at 0.127 -10.4902 90)
			(unlocked yes)
			(layer "F.Fab")
			(hide yes)
			(effects
				(font
					(size 1.016 1.016)
					(thickness 0.1524)
				)
			)
		)
		(duplicate_pad_numbers_are_jumpers no)
		(fp_line
			(start 1.651 -1.778)
			(end -1.651 -1.778)
			(stroke
				(width 0.1524)
				(type default)
			)
			(layer "F.SilkS")
		)
		(fp_line
			(start -1.651 -1.778)
			(end -1.651 1.778)
			(stroke
				(width 0.1524)
				(type default)
			)
			(layer "F.SilkS")
		)
		(fp_line
			(start 1.651 1.778)
			(end 1.651 -1.778)
			(stroke
				(width 0.1524)
				(type default)
			)
			(layer "F.SilkS")
		)
		(fp_line
			(start -1.651 1.778)
			(end 1.651 1.778)
			(stroke
				(width 0.1524)
				(type default)
			)
			(layer "F.SilkS")
		)
		(fp_poly
			(pts
				(xy -1.778 1.8796) (xy -1.778 -1.8796) (xy 1.778 -1.8796) (xy 1.778 1.8796)
			)
			(stroke
				(width 0)
				(type default)
			)
			(fill no)
			(layer "F.CrtYd")
		)
		(fp_poly
			(pts
				(xy -1.778 1.8796) (xy -1.778 -1.8796) (xy 1.778 -1.8796) (xy 1.778 1.8796)
			)
			(stroke
				(width 0)
				(type default)
			)
			(fill no)
			(layer "F.Fab")
		)
		(pad "D" smd custom
			(at 0 -0.9525 90)
			(size 0.1905 0.1905)
			(layers "F.Cu" "F.Mask" "F.Paste")
			(net "SSD14_CLK0_OE_MOS_N")
			(options
				(clearance outline)
				(anchor circle)
			)
			(primitives
				(gr_poly
					(pts
						(arc
							(start -0.1778 0.5715)
							(mid -0.321484 0.511984)
							(end -0.381 0.3683)
						)
						(arc
							(start -0.381 -0.3683)
							(mid -0.321484 -0.511984)
							(end -0.1778 -0.5715)
						)
						(arc
							(start 0.1778 -0.5715)
							(mid 0.321484 -0.511984)
							(end 0.381 -0.3683)
						)
						(arc
							(start 0.381 0.3683)
							(mid 0.321484 0.511984)
							(end 0.1778 0.5715)
						)
					)
					(width 0)
					(fill yes)
				)
			)
		)
		(pad "G" smd custom
			(at -0.98425 0.9525 90)
			(size 0.1905 0.1905)
			(layers "F.Cu" "F.Mask" "F.Paste")
			(net "SSD14_CLK0_OE_R_N")
			(options
				(clearance outline)
				(anchor circle)
			)
			(primitives
				(gr_poly
					(pts
						(arc
							(start -0.1778 0.5715)
							(mid -0.321484 0.511984)
							(end -0.381 0.3683)
						)
						(arc
							(start -0.381 -0.3683)
							(mid -0.321484 -0.511984)
							(end -0.1778 -0.5715)
						)
						(arc
							(start 0.1778 -0.5715)
							(mid 0.321484 -0.511984)
							(end 0.381 -0.3683)
						)
						(arc
							(start 0.381 0.3683)
							(mid 0.321484 0.511984)
							(end 0.1778 0.5715)
						)
					)
					(width 0)
					(fill yes)
				)
			)
		)
		(pad "S" smd custom
			(at 0.98425 0.9525 90)
			(size 0.1905 0.1905)
			(layers "F.Cu" "F.Mask" "F.Paste")
			(net "GND")
			(options
				(clearance outline)
				(anchor circle)
			)
			(primitives
				(gr_poly
					(pts
						(arc
							(start -0.1778 0.5715)
							(mid -0.321484 0.511984)
							(end -0.381 0.3683)
						)
						(arc
							(start -0.381 -0.3683)
							(mid -0.321484 -0.511984)
							(end -0.1778 -0.5715)
						)
						(arc
							(start 0.1778 -0.5715)
							(mid 0.321484 -0.511984)
							(end 0.381 -0.3683)
						)
						(arc
							(start 0.381 0.3683)
							(mid 0.321484 0.511984)
							(end 0.1778 0.5715)
						)
					)
					(width 0)
					(fill yes)
				)
			)
		)
	)
	(footprint ""
		(layer "F.Cu")
		(at 23.1648 -190.119)
		(property "Reference" "R559"
			(at 0 0 0)
			(layer "F.SilkS")
			(hide yes)
			(effects
				(font
					(size 1.27 1.27)
				)
			)
		)
		(property "Value" "200KR2F-L-GP"
			(at 0.064008 -3.993896 0)
			(unlocked yes)
			(layer "F.Fab")
			(hide yes)
			(effects
				(font
					(size 1.016 1.016)
					(thickness 0.1524)
				)
			)
		)
		(property "Device Type" "R402H16"
			(at 0.064008 -5.517896 0)
			(unlocked yes)
			(layer "F.Fab")
			(hide yes)
			(effects
				(font
					(size 1.016 1.016)
					(thickness 0.1524)
				)
			)
		)
		(duplicate_pad_numbers_are_jumpers no)
		(fp_line
			(start -0.508 -0.9398)
			(end -0.508 0.9398)
			(stroke
				(width 0.1524)
				(type default)
			)
			(layer "F.SilkS")
		)
		(fp_line
			(start 0.508 -0.9398)
			(end -0.508 -0.9398)
			(stroke
				(width 0.1524)
				(type default)
			)
			(layer "F.SilkS")
		)
		(fp_rect
			(start -0.508 0.9398)
			(end 0.508 -0.9398)
			(stroke
				(width 0)
				(type default)
			)
			(fill no)
			(layer "F.CrtYd")
		)
		(fp_rect
			(start -0.508 0.9398)
			(end 0.508 -0.9398)
			(stroke
				(width 0)
				(type default)
			)
			(fill no)
			(layer "F.Fab")
		)
		(pad "1" smd custom
			(at 0 -0.4445)
			(size 0.1397 0.1397)
			(layers "F.Cu" "F.Mask" "F.Paste")
			(net "SW_SSD8_R")
			(options
				(clearance outline)
				(anchor circle)
			)
			(primitives
				(gr_poly
					(pts
						(arc
							(start -0.1778 -0.2794)
							(mid -0.249642 -0.249642)
							(end -0.2794 -0.1778)
						)
						(arc
							(start -0.2794 0.1778)
							(mid -0.249642 0.249642)
							(end -0.1778 0.2794)
						)
						(arc
							(start 0.1778 0.2794)
							(mid 0.249642 0.249642)
							(end 0.2794 0.1778)
						)
						(arc
							(start 0.2794 -0.1778)
							(mid 0.249642 -0.249642)
							(end 0.1778 -0.2794)
						)
					)
					(width 0)
					(fill yes)
				)
			)
		)
		(pad "2" smd custom
			(at 0 0.4445)
			(size 0.1397 0.1397)
			(layers "F.Cu" "F.Mask" "F.Paste")
			(net "SW_SSD8_N")
			(options
				(clearance outline)
				(anchor circle)
			)
			(primitives
				(gr_poly
					(pts
						(arc
							(start -0.1778 -0.2794)
							(mid -0.249642 -0.249642)
							(end -0.2794 -0.1778)
						)
						(arc
							(start -0.2794 0.1778)
							(mid -0.249642 0.249642)
							(end -0.1778 0.2794)
						)
						(arc
							(start 0.1778 0.2794)
							(mid 0.249642 0.249642)
							(end 0.2794 0.1778)
						)
						(arc
							(start 0.2794 -0.1778)
							(mid 0.249642 -0.249642)
							(end 0.1778 -0.2794)
						)
					)
					(width 0)
					(fill yes)
				)
			)
		)
	)
)
